# BARRELEYE_G2-FPDB_POST-PVT-X02-BOM-X05-20171123_Final.xls.xlsx — Summary (bom)
| PLATFORM SOURCING AND PSL COMPLIANCE |  |  |  |  |  |  |  |  |  |
| Platform Name: |  |  |  |  |  |  |  |  |  |
| REVISION HISTORY |  |  |  |  |  |  |  |  |  |
| BOM Revision: | ECR # | Revision Description | Originator | Date |  |  |  |  |  |
| X02 |  |  |  | 42886 |  |  |  |  |  |
| X05 |  |  |  | 43060 |  |  |  |  |  |
| Commodity Sourcing | # of components (X00 BOM) | % of Total | # of components (X01 BOM) | % of Total | # of components (X02 BOM) | % of Total | # of components (RTS) | % of Total | Risk Mitigation Plans in Place |
| Sole Source |  |  |  |  |  |  |  |  |  |
| Single Source |  |  |  |  |  |  | 24 | 0.1951219512 |  |
| Multiple |  |  |  |  |  |  | 99 | 0.8048780488 | NA |
| Total |  |  |  |  |  |  | 123 | 1 | NA |
|  |  | # of components | # of components aligned with Customer PSL* | % PSL alignment |  |  |  |  |  |
| Class 1 (Customer Managed) |  |  |  |  |  |  |  |  |  |
| Class 2 (ODM Managed to Customer PSL) |  |  |  |  |  |  |  |  |  |
| All other components(ODM Managed to ODM PSL) |  |  |  |  |  |  |  |  |  |
| *RFQ and/or Contract will list requirements for complying with Customer's PSL |  |  |  |  |  |  |  |  |  |
| Reference for quotation |  |  |  |  |  |  |  |  |  |
